# TIMECARD (Time Appliance Project (Time Card)) — schematic netlist excerpt (pin names and nets, part order shuffled) for the footprints in the layout excerpt that follows; sources: Cadence DE-HDL packaged netlist, KiCad conversion of R4006-B0001-02_R01.brd

C82  CAPACITOR  0.1UF 10V 10%  pkg SMC_0402R_H022  page 23 : \1\ = XP3R3V_FPGA ; \2\ = SG
R217  RESISTOR  100OHM 1%  pkg SMC_0402R_H016  page 10 : \1\ = XP3R3V_FPGA ; \2\ = FPGA_M1

(kicad_pcb
	(version 20260206)
	(generator "pcbnew")
	(generator_version "10.0")
	(general
		(thickness 1.6)
		(legacy_teardrops no)
	)
	(paper "A4")
	(title_block
		(title "timecard-production-celestica-r4006 — R4006-B0001-02_R01.brd")
		(comment 1 "Time Appliance Project (Time Card) / footprints 783-784 of 1113")
	)
	(layers
		(0 "F.Cu" signal "TOP")
		(4 "In1.Cu" signal "L02_GND1")
		(6 "In2.Cu" signal "L03_SIG1")
		(8 "In3.Cu" signal "L04_GND2")
		(10 "In4.Cu" signal "L05_VCC1")
		(12 "In5.Cu" signal "L06_VCC2")
		(14 "In6.Cu" signal "L07_GND3")
		(16 "In7.Cu" signal "L08_SIG2")
		(18 "In8.Cu" signal "L09_GND4")
		(2 "B.Cu" signal "BOTTOM")
		(9 "F.Adhes" user "F.Adhesive")
		(11 "B.Adhes" user "B.Adhesive")
		(13 "F.Paste" user "Package Geometry/Pastemask Top")
		(15 "B.Paste" user "Package Geometry/Pastemask Bottom")
		(5 "F.SilkS" user "Ref Des/Silkscreen Top")
		(7 "B.SilkS" user "Ref Des/Silkscreen Bottom")
		(1 "F.Mask" user "Board Geometry/Soldermask Top")
		(3 "B.Mask" user "Board Geometry/Soldermask Bottom")
		(17 "Dwgs.User" user "User.Drawings")
		(19 "Cmts.User" user "User.Comments")
		(21 "Eco1.User" user "User.Eco1")
		(23 "Eco2.User" user "User.Eco2")
		(25 "Edge.Cuts" user "Board Geometry/Outline")
		(27 "Margin" user)
		(31 "F.CrtYd" user "Package Geometry/Place Bound Top")
		(29 "B.CrtYd" user "Package Geometry/Place Bound Bottom")
		(35 "F.Fab" user "Ref Des/Assembly Top")
		(33 "B.Fab" user "Ref Des/Assembly Bottom")
	)
	(footprint ""
		(layer "B.Cu")
		(at 16.6624 -15.621 180)
		(property "Reference" "C82"
			(at -0.2286 -1.18237 0)
			(unlocked yes)
			(layer "B.SilkS")
			(effects
				(font
					(size 0.7874 0.5842)
					(thickness 0.1524)
				)
				(justify mirror)
			)
		)
		(property "Value" "VAL*"
			(at -0.0762 2.067306 180)
			(unlocked yes)
			(layer "B.Fab")
			(hide yes)
			(effects
				(font
					(size 0.7874 0.5842)
					(thickness 0.1524)
				)
				(justify mirror)
			)
		)
		(property "Device Type" "CAPACITOR-G105-0B104-CK,0.1UF,A"
			(at -0.0508 1.127506 180)
			(unlocked yes)
			(layer "B.Fab")
			(hide yes)
			(effects
				(font
					(size 0.7874 0.5842)
					(thickness 0.1524)
				)
				(justify mirror)
			)
		)
		(property "User Part Number" "PARTNUM*"
			(at -0.1016 4.023106 180)
			(unlocked yes)
			(layer "Cmts.User")
			(hide yes)
			(effects
				(font
					(size 0.7874 0.5842)
					(thickness 0.1524)
				)
				(justify mirror)
			)
		)
		(property "Tolerance" "TOL*"
			(at -0.0762 3.032506 180)
			(unlocked yes)
			(layer "Cmts.User")
			(hide yes)
			(effects
				(font
					(size 0.7874 0.5842)
					(thickness 0.1524)
				)
				(justify mirror)
			)
		)
		(duplicate_pad_numbers_are_jumpers no)
		(fp_line
			(start 1.143 0.5588)
			(end -1.143 0.5588)
			(stroke
				(width 0.1)
				(type default)
			)
			(layer "B.SilkS")
		)
		(fp_line
			(start 1.143 -0.5588)
			(end 1.143 0.5588)
			(stroke
				(width 0.1)
				(type default)
			)
			(layer "B.SilkS")
		)
		(fp_line
			(start -1.143 0.5588)
			(end -1.143 -0.5588)
			(stroke
				(width 0.1)
				(type default)
			)
			(layer "B.SilkS")
		)
		(fp_line
			(start -1.143 -0.5588)
			(end 1.143 -0.5588)
			(stroke
				(width 0.1)
				(type default)
			)
			(layer "B.SilkS")
		)
		(fp_rect
			(start -1.143 0.5588)
			(end 1.143 -0.5588)
			(stroke
				(width 0)
				(type default)
			)
			(fill no)
			(layer "B.CrtYd")
		)
		(fp_line
			(start 0.508 0.3048)
			(end -0.508 0.3048)
			(stroke
				(width 0.1)
				(type default)
			)
			(layer "B.Fab")
		)
		(fp_line
			(start 0.508 -0.3048)
			(end 0.508 0.3048)
			(stroke
				(width 0.1)
				(type default)
			)
			(layer "B.Fab")
		)
		(fp_line
			(start -0.508 0.3048)
			(end -0.508 -0.3048)
			(stroke
				(width 0.1)
				(type default)
			)
			(layer "B.Fab")
		)
		(fp_line
			(start -0.508 -0.3048)
			(end 0.508 -0.3048)
			(stroke
				(width 0.1)
				(type default)
			)
			(layer "B.Fab")
		)
		(pad "1" smd rect
			(at 0.5334 0)
			(size 0.7112 0.6096)
			(layers "B.Cu" "B.Mask" "B.Paste")
			(net "XP3R3V_FPGA")
		)
		(pad "2" smd rect
			(at -0.5334 0)
			(size 0.7112 0.6096)
			(layers "B.Cu" "B.Mask" "B.Paste")
			(net "SG")
		)
		(zone
			(layer "B.Cu")
			(hatch none 0.5)
			(connect_pads
				(clearance 0)
			)
			(min_thickness 0.25)
			(keepout
				(tracks allowed)
				(vias not_allowed)
				(pads allowed)
				(copperpour not_allowed)
				(footprints allowed)
			)
			(placement
				(enabled no)
				(sheetname "")
			)
			(fill
				(thermal_gap 0.5)
				(thermal_bridge_width 0.5)
				(island_removal_mode 0)
			)
			(polygon
				(pts
					(xy 16.7386 -15.9258) (xy 16.5862 -15.9258) (xy 16.5862 -15.3162) (xy 16.7386 -15.3162)
				)
			)
		)
	)
	(footprint ""
		(layer "B.Cu")
		(at 124.587 -41.402)
		(property "Reference" "R217"
			(at 3.429 0.16637 0)
			(unlocked yes)
			(layer "B.SilkS")
			(effects
				(font
					(size 0.7874 0.5842)
					(thickness 0.1524)
				)
				(justify mirror)
			)
		)
		(property "Value" "VAL*"
			(at -0.02032 2.13233 0)
			(unlocked yes)
			(layer "B.Fab")
			(hide yes)
			(effects
				(font
					(size 0.7874 0.5842)
					(thickness 0.1524)
				)
				(justify mirror)
			)
		)
		(property "Tolerance" "TOL*"
			(at -0.044704 3.05435 0)
			(unlocked yes)
			(layer "Cmts.User")
			(hide yes)
			(effects
				(font
					(size 0.7874 0.5842)
					(thickness 0.1524)
				)
				(justify mirror)
			)
		)
		(property "User Part Number" "PARTNUM*"
			(at -0.02032 4.024884 0)
			(unlocked yes)
			(layer "Cmts.User")
			(hide yes)
			(effects
				(font
					(size 0.7874 0.5842)
					(thickness 0.1524)
				)
				(justify mirror)
			)
		)
		(property "Device Type" "RESISTOR-G155-11000-01,100OHM,A"
			(at -0.008382 1.210564 0)
			(unlocked yes)
			(layer "B.Fab")
			(hide yes)
			(effects
				(font
					(size 0.7874 0.5842)
					(thickness 0.1524)
				)
				(justify mirror)
			)
		)
		(duplicate_pad_numbers_are_jumpers no)
		(fp_line
			(start -1.143 -0.5588)
			(end 1.143 -0.5588)
			(stroke
				(width 0.1)
				(type default)
			)
			(layer "B.SilkS")
		)
		(fp_line
			(start -1.143 0.5588)
			(end -1.143 -0.5588)
			(stroke
				(width 0.1)
				(type default)
			)
			(layer "B.SilkS")
		)
		(fp_line
			(start 1.143 -0.5588)
			(end 1.143 0.5588)
			(stroke
				(width 0.1)
				(type default)
			)
			(layer "B.SilkS")
		)
		(fp_line
			(start 1.143 0.5588)
			(end -1.143 0.5588)
			(stroke
				(width 0.1)
				(type default)
			)
			(layer "B.SilkS")
		)
		(fp_rect
			(start -1.143 0.5588)
			(end 1.143 -0.5588)
			(stroke
				(width 0)
				(type default)
			)
			(fill no)
			(layer "B.CrtYd")
		)
		(fp_line
			(start -0.508 -0.3048)
			(end 0.508 -0.3048)
			(stroke
				(width 0.1)
				(type default)
			)
			(layer "B.Fab")
		)
		(fp_line
			(start -0.508 0.3048)
			(end -0.508 -0.3048)
			(stroke
				(width 0.1)
				(type default)
			)
			(layer "B.Fab")
		)
		(fp_line
			(start 0.508 -0.3048)
			(end 0.508 0.3048)
			(stroke
				(width 0.1)
				(type default)
			)
			(layer "B.Fab")
		)
		(fp_line
			(start 0.508 0.3048)
			(end -0.508 0.3048)
			(stroke
				(width 0.1)
				(type default)
			)
			(layer "B.Fab")
		)
		(pad "1" smd rect
			(at 0.5334 0 180)
			(size 0.7112 0.6096)
			(layers "B.Cu" "B.Mask" "B.Paste")
			(net "XP3R3V_FPGA")
		)
		(pad "2" smd rect
			(at -0.5334 0 180)
			(size 0.7112 0.6096)
			(layers "B.Cu" "B.Mask" "B.Paste")
			(net "FPGA_M1")
		)
		(zone
			(layer "B.Cu")
			(hatch none 0.5)
			(connect_pads
				(clearance 0)
			)
			(min_thickness 0.25)
			(keepout
				(tracks allowed)
				(vias not_allowed)
				(pads allowed)
				(copperpour not_allowed)
				(footprints allowed)
			)
			(placement
				(enabled no)
				(sheetname "")
			)
			(fill
				(thermal_gap 0.5)
				(thermal_bridge_width 0.5)
				(island_removal_mode 0)
			)
			(polygon
				(pts
					(xy 124.5108 -41.0972) (xy 124.6632 -41.0972) (xy 124.6632 -41.7068) (xy 124.5108 -41.7068)
				)
			)
		)
	)
)
